(kicad_pcb
	(version 20260206)
	(generator "pcbnew")
	(generator_version "10.0")
	(general
		(thickness 1.6)
		(legacy_teardrops no)
	)
	(paper "A4")
	(title_block
		(title "dpb — 14545-sa.0730WZS0815.brd")
		(comment 1 "Honey Badger (Wiwynn) / footprints 787-792 of 1066")
	)
	(layers
		(0 "F.Cu" signal "TOP")
		(4 "In1.Cu" signal "L2GND")
		(6 "In2.Cu" signal "L3")
		(8 "In3.Cu" signal "L4VCC")
		(10 "In4.Cu" signal "L5VCC")
		(12 "In5.Cu" signal "L6")
		(14 "In6.Cu" signal "L7GND")
		(2 "B.Cu" signal "BOTTOM")
		(9 "F.Adhes" user "F.Adhesive")
		(11 "B.Adhes" user "B.Adhesive")
		(13 "F.Paste" user "Package Geometry/Pastemask Top")
		(15 "B.Paste" user "Package Geometry/Pastemask Bottom")
		(5 "F.SilkS" user "Ref Des/Silkscreen Top")
		(7 "B.SilkS" user "Ref Des/Silkscreen Bottom")
		(1 "F.Mask" user "Board Geometry/Soldermask Top")
		(3 "B.Mask" user "Board Geometry/Soldermask Bottom")
		(17 "Dwgs.User" user "User.Drawings")
		(19 "Cmts.User" user "User.Comments")
		(21 "Eco1.User" user "User.Eco1")
		(23 "Eco2.User" user "User.Eco2")
		(25 "Edge.Cuts" user "Board Geometry/Outline")
		(27 "Margin" user)
		(31 "F.CrtYd" user "Package Geometry/Place Bound Top")
		(29 "B.CrtYd" user "Package Geometry/Place Bound Bottom")
		(35 "F.Fab" user "Ref Des/Assembly Top")
		(33 "B.Fab" user "Ref Des/Assembly Bottom")
	)
	(footprint ""
		(layer "F.Cu")
		(at 218.947746 -32.2707 180)
		(property "Reference" "PTC2"
			(at 0 0 180)
			(layer "F.SilkS")
			(hide yes)
			(effects
				(font
					(size 1.27 1.27)
				)
			)
		)
		(property "Value" "ST330U10VDM-2GP"
			(at 0 -9.6012 180)
			(unlocked yes)
			(layer "F.Fab")
			(hide yes)
			(effects
				(font
					(size 1.016 1.016)
					(thickness 0.1524)
				)
			)
		)
		(property "Device Type" "CT7343H150"
			(at 0 -11.1252 180)
			(unlocked yes)
			(layer "F.Fab")
			(hide yes)
			(effects
				(font
					(size 1.016 1.016)
					(thickness 0.1524)
				)
			)
		)
		(duplicate_pad_numbers_are_jumpers no)
		(fp_line
			(start 2.286 4.8768)
			(end -2.286 4.8768)
			(stroke
				(width 0.1524)
				(type default)
			)
			(layer "F.SilkS")
		)
		(fp_line
			(start 2.286 2.032)
			(end 2.286 4.8768)
			(stroke
				(width 0.1524)
				(type default)
			)
			(layer "F.SilkS")
		)
		(fp_line
			(start 2.286 -2.032)
			(end 2.286 -4.8768)
			(stroke
				(width 0.1524)
				(type default)
			)
			(layer "F.SilkS")
		)
		(fp_line
			(start 2.286 -4.8768)
			(end -2.286 -4.8768)
			(stroke
				(width 0.1524)
				(type default)
			)
			(layer "F.SilkS")
		)
		(fp_line
			(start 2.1082 -4.699)
			(end -2.1082 -4.699)
			(stroke
				(width 0.508)
				(type default)
			)
			(layer "F.SilkS")
		)
		(fp_line
			(start -2.286 4.8768)
			(end -2.286 2.032)
			(stroke
				(width 0.1524)
				(type default)
			)
			(layer "F.SilkS")
		)
		(fp_line
			(start -2.286 -4.8768)
			(end -2.286 -2.032)
			(stroke
				(width 0.1524)
				(type default)
			)
			(layer "F.SilkS")
		)
		(fp_rect
			(start -2.1463 3.6449)
			(end 2.1463 -3.6449)
			(stroke
				(width 0)
				(type default)
			)
			(fill no)
			(layer "F.CrtYd")
		)
		(fp_poly
			(pts
				(xy -2.54 4.953) (xy -2.54 4.2926) (xy -3.81 4.2926) (xy -3.81 -4.2926) (xy -2.54 -4.2926) (xy -2.54 -4.953)
				(xy 2.54 -4.953) (xy 2.54 -4.2926) (xy 3.81 -4.2926) (xy 3.81 -1.6256) (xy 2.1463 -1.6256) (xy 2.1463 -3.6449)
				(xy -2.1463 -3.6449) (xy -2.1463 3.6449) (xy 2.1463 3.6449) (xy 2.1463 -1.6129) (xy 3.81 -1.6129)
				(xy 3.81 4.2926) (xy 2.54 4.2926) (xy 2.54 4.953)
			)
			(stroke
				(width 0)
				(type default)
			)
			(fill no)
			(layer "F.CrtYd")
		)
		(fp_rect
			(start 2.54 4.2926)
			(end 3.81 -4.2926)
			(stroke
				(width 0)
				(type default)
			)
			(fill no)
			(layer "F.Fab")
		)
		(fp_rect
			(start -2.54 4.953)
			(end 2.54 -4.953)
			(stroke
				(width 0)
				(type default)
			)
			(fill no)
			(layer "F.Fab")
		)
		(fp_rect
			(start -3.81 4.2926)
			(end -2.54 -4.2926)
			(stroke
				(width 0)
				(type default)
			)
			(fill no)
			(layer "F.Fab")
		)
		(pad "1" smd rect
			(at 0 -3.1496 180)
			(size 2.413 2.286)
			(layers "F.Cu" "F.Mask" "F.Paste")
			(net "P5VA")
		)
		(pad "2" smd rect
			(at 0 3.1496 180)
			(size 2.413 2.286)
			(layers "F.Cu" "F.Mask" "F.Paste")
			(net "GND")
		)
		(zone
			(layer "F.Cu")
			(hatch none 0.5)
			(connect_pads
				(clearance 0)
			)
			(min_thickness 0.25)
			(keepout
				(tracks allowed)
				(vias not_allowed)
				(pads allowed)
				(copperpour not_allowed)
				(footprints allowed)
			)
			(placement
				(enabled no)
				(sheetname "")
			)
			(fill
				(thermal_gap 0.5)
				(thermal_bridge_width 0.5)
				(island_removal_mode 0)
			)
			(polygon
				(pts
					(xy 217.436446 -30.5816) (xy 217.436446 -27.6733) (xy 220.459046 -27.6733) (xy 220.459046 -30.5689)
					(xy 220.459046 -30.8991) (xy 217.436446 -30.8991)
				)
			)
		)
		(zone
			(layer "F.Cu")
			(hatch none 0.5)
			(connect_pads
				(clearance 0)
			)
			(min_thickness 0.25)
			(keepout
				(tracks allowed)
				(vias not_allowed)
				(pads allowed)
				(copperpour not_allowed)
				(footprints allowed)
			)
			(placement
				(enabled no)
				(sheetname "")
			)
			(fill
				(thermal_gap 0.5)
				(thermal_bridge_width 0.5)
				(island_removal_mode 0)
			)
			(polygon
				(pts
					(xy 220.459046 -36.8681) (xy 217.436446 -36.8681) (xy 217.436446 -33.9725) (xy 217.436446 -33.6423)
					(xy 220.459046 -33.6423) (xy 220.459046 -33.9725)
				)
			)
		)
	)
	(footprint ""
		(layer "F.Cu")
		(at 48.640746 -223.167702 180)
		(property "Reference" "C302"
			(at 0 0 180)
			(layer "F.SilkS")
			(hide yes)
			(effects
				(font
					(size 1.27 1.27)
				)
			)
		)
		(property "Value" "SC10U25V6KX-1GP"
			(at -0.0762 -5.1308 180)
			(unlocked yes)
			(layer "F.Fab")
			(hide yes)
			(effects
				(font
					(size 1.016 1.016)
					(thickness 0.1524)
				)
			)
		)
		(property "Device Type" "C1206H71"
			(at -0.127 -6.6548 180)
			(unlocked yes)
			(layer "F.Fab")
			(hide yes)
			(effects
				(font
					(size 1.016 1.016)
					(thickness 0.1524)
				)
			)
		)
		(duplicate_pad_numbers_are_jumpers no)
		(fp_line
			(start 1.016 2.2352)
			(end -1.016 2.2352)
			(stroke
				(width 0.1524)
				(type default)
			)
			(layer "F.SilkS")
		)
		(fp_line
			(start 1.016 0.8382)
			(end 1.016 2.2352)
			(stroke
				(width 0.1524)
				(type default)
			)
			(layer "F.SilkS")
		)
		(fp_line
			(start 1.016 -2.2352)
			(end 1.016 -0.8382)
			(stroke
				(width 0.1524)
				(type default)
			)
			(layer "F.SilkS")
		)
		(fp_line
			(start -1.016 2.2352)
			(end -1.016 0.8382)
			(stroke
				(width 0.1524)
				(type default)
			)
			(layer "F.SilkS")
		)
		(fp_line
			(start -1.016 -0.8382)
			(end -1.016 -2.2352)
			(stroke
				(width 0.1524)
				(type default)
			)
			(layer "F.SilkS")
		)
		(fp_line
			(start -1.016 -2.2352)
			(end 1.016 -2.2352)
			(stroke
				(width 0.1524)
				(type default)
			)
			(layer "F.SilkS")
		)
		(fp_rect
			(start -1.0922 2.3114)
			(end 1.0922 -2.3114)
			(stroke
				(width 0)
				(type default)
			)
			(fill no)
			(layer "F.CrtYd")
		)
		(fp_poly
			(pts
				(xy 1.0922 -2.3114) (xy 1.0922 2.3114) (xy -1.0922 2.3114) (xy -1.0922 -2.3114)
			)
			(stroke
				(width 0)
				(type default)
			)
			(fill no)
			(layer "F.Fab")
		)
		(pad "1" smd rect
			(at 0 -1.397 180)
			(size 1.651 1.27)
			(layers "F.Cu" "F.Mask" "F.Paste")
			(net "P12V_HDD12")
		)
		(pad "2" smd rect
			(at 0 1.397 180)
			(size 1.651 1.27)
			(layers "F.Cu" "F.Mask" "F.Paste")
			(net "GND")
		)
	)
	(footprint ""
		(layer "F.Cu")
		(at 61.3918 -171.9834 -90)
		(property "Reference" "R385"
			(at 0 0 270)
			(layer "F.SilkS")
			(hide yes)
			(effects
				(font
					(size 1.27 1.27)
				)
			)
		)
		(property "Value" "10KR2F-2-GP"
			(at 0.064008 -3.993896 270)
			(unlocked yes)
			(layer "F.Fab")
			(hide yes)
			(effects
				(font
					(size 1.016 1.016)
					(thickness 0.1524)
				)
			)
		)
		(property "Device Type" "R402H16"
			(at 0.064008 -5.517896 270)
			(unlocked yes)
			(layer "F.Fab")
			(hide yes)
			(effects
				(font
					(size 1.016 1.016)
					(thickness 0.1524)
				)
			)
		)
		(duplicate_pad_numbers_are_jumpers no)
		(fp_line
			(start -0.508 -0.9398)
			(end -0.508 0.9398)
			(stroke
				(width 0.1524)
				(type default)
			)
			(layer "F.SilkS")
		)
		(fp_line
			(start 0.508 -0.9398)
			(end -0.508 -0.9398)
			(stroke
				(width 0.1524)
				(type default)
			)
			(layer "F.SilkS")
		)
		(fp_rect
			(start -0.508 0.9398)
			(end 0.508 -0.9398)
			(stroke
				(width 0)
				(type default)
			)
			(fill no)
			(layer "F.CrtYd")
		)
		(fp_rect
			(start -0.508 0.9398)
			(end 0.508 -0.9398)
			(stroke
				(width 0)
				(type default)
			)
			(fill no)
			(layer "F.Fab")
		)
		(pad "1" smd custom
			(at 0 -0.4445 270)
			(size 0.1397 0.1397)
			(layers "F.Cu" "F.Mask" "F.Paste")
			(net "P12V")
			(options
				(clearance outline)
				(anchor circle)
			)
			(primitives
				(gr_poly
					(pts
						(arc
							(start -0.1778 -0.2794)
							(mid -0.249642 -0.249642)
							(end -0.2794 -0.1778)
						)
						(arc
							(start -0.2794 0.1778)
							(mid -0.249642 0.249642)
							(end -0.1778 0.2794)
						)
						(arc
							(start 0.1778 0.2794)
							(mid 0.249642 0.249642)
							(end 0.2794 0.1778)
						)
						(arc
							(start 0.2794 -0.1778)
							(mid 0.249642 -0.249642)
							(end 0.1778 -0.2794)
						)
					)
					(width 0)
					(fill yes)
				)
			)
		)
		(pad "2" smd custom
			(at 0 0.4445 270)
			(size 0.1397 0.1397)
			(layers "F.Cu" "F.Mask" "F.Paste")
			(net "HDD8_LED_G")
			(options
				(clearance outline)
				(anchor circle)
			)
			(primitives
				(gr_poly
					(pts
						(arc
							(start -0.1778 -0.2794)
							(mid -0.249642 -0.249642)
							(end -0.2794 -0.1778)
						)
						(arc
							(start -0.2794 0.1778)
							(mid -0.249642 0.249642)
							(end -0.1778 0.2794)
						)
						(arc
							(start 0.1778 0.2794)
							(mid 0.249642 0.249642)
							(end 0.2794 0.1778)
						)
						(arc
							(start 0.2794 -0.1778)
							(mid 0.249642 -0.249642)
							(end 0.1778 -0.2794)
						)
					)
					(width 0)
					(fill yes)
				)
			)
		)
	)
	(footprint ""
		(layer "F.Cu")
		(at 57.149746 -388.6327 180)
		(property "Reference" "C206"
			(at 0 0 180)
			(layer "F.SilkS")
			(hide yes)
			(effects
				(font
					(size 1.27 1.27)
				)
			)
		)
		(property "Value" "SC10U16V6KX-2GP"
			(at -0.0762 -5.1308 180)
			(unlocked yes)
			(layer "F.Fab")
			(hide yes)
			(effects
				(font
					(size 1.016 1.016)
					(thickness 0.1524)
				)
			)
		)
		(property "Device Type" "C1206H71"
			(at -0.127 -6.6548 180)
			(unlocked yes)
			(layer "F.Fab")
			(hide yes)
			(effects
				(font
					(size 1.016 1.016)
					(thickness 0.1524)
				)
			)
		)
		(duplicate_pad_numbers_are_jumpers no)
		(fp_line
			(start 1.016 2.2352)
			(end -1.016 2.2352)
			(stroke
				(width 0.1524)
				(type default)
			)
			(layer "F.SilkS")
		)
		(fp_line
			(start 1.016 0.8382)
			(end 1.016 2.2352)
			(stroke
				(width 0.1524)
				(type default)
			)
			(layer "F.SilkS")
		)
		(fp_line
			(start 1.016 -2.2352)
			(end 1.016 -0.8382)
			(stroke
				(width 0.1524)
				(type default)
			)
			(layer "F.SilkS")
		)
		(fp_line
			(start -1.016 2.2352)
			(end -1.016 0.8382)
			(stroke
				(width 0.1524)
				(type default)
			)
			(layer "F.SilkS")
		)
		(fp_line
			(start -1.016 -0.8382)
			(end -1.016 -2.2352)
			(stroke
				(width 0.1524)
				(type default)
			)
			(layer "F.SilkS")
		)
		(fp_line
			(start -1.016 -2.2352)
			(end 1.016 -2.2352)
			(stroke
				(width 0.1524)
				(type default)
			)
			(layer "F.SilkS")
		)
		(fp_rect
			(start -1.0922 2.3114)
			(end 1.0922 -2.3114)
			(stroke
				(width 0)
				(type default)
			)
			(fill no)
			(layer "F.CrtYd")
		)
		(fp_poly
			(pts
				(xy 1.0922 -2.3114) (xy 1.0922 2.3114) (xy -1.0922 2.3114) (xy -1.0922 -2.3114)
			)
			(stroke
				(width 0)
				(type default)
			)
			(fill no)
			(layer "F.Fab")
		)
		(pad "1" smd rect
			(at 0 -1.397 180)
			(size 1.651 1.27)
			(layers "F.Cu" "F.Mask" "F.Paste")
			(net "P5V_HDD6")
		)
		(pad "2" smd rect
			(at 0 1.397 180)
			(size 1.651 1.27)
			(layers "F.Cu" "F.Mask" "F.Paste")
			(net "GND")
		)
	)
	(footprint ""
		(layer "F.Cu")
		(at 71.500746 -83.9597)
		(property "Reference" "U28"
			(at 0 0 0)
			(layer "F.SilkS")
			(hide yes)
			(effects
				(font
					(size 1.27 1.27)
				)
			)
		)
		(property "Value" "74LVC1G08GW-1-GP"
			(at -2.3368 -8.6868 0)
			(unlocked yes)
			(layer "F.Fab")
			(hide yes)
			(effects
				(font
					(size 1.016 1.016)
					(thickness 0.1524)
				)
			)
		)
		(property "Device Type" "SC70-5H44"
			(at -2.3114 -10.414 0)
			(unlocked yes)
			(layer "F.Fab")
			(hide yes)
			(effects
				(font
					(size 1.016 1.016)
					(thickness 0.1524)
				)
			)
		)
		(duplicate_pad_numbers_are_jumpers no)
		(fp_line
			(start -1.27 -1.7018)
			(end 1.27 -1.7018)
			(stroke
				(width 0.1524)
				(type default)
			)
			(layer "F.SilkS")
		)
		(fp_line
			(start -1.27 1.7018)
			(end -1.27 -1.7018)
			(stroke
				(width 0.1524)
				(type default)
			)
			(layer "F.SilkS")
		)
		(fp_line
			(start 0.6604 -1.8034)
			(end 1.3843 -1.8034)
			(stroke
				(width 0.3302)
				(type default)
			)
			(layer "F.SilkS")
		)
		(fp_line
			(start 1.27 -1.7018)
			(end 1.27 1.7018)
			(stroke
				(width 0.1524)
				(type default)
			)
			(layer "F.SilkS")
		)
		(fp_line
			(start 1.27 1.7018)
			(end -1.27 1.7018)
			(stroke
				(width 0.1524)
				(type default)
			)
			(layer "F.SilkS")
		)
		(fp_line
			(start 1.3843 -1.8034)
			(end 1.3843 -1.1176)
			(stroke
				(width 0.3302)
				(type default)
			)
			(layer "F.SilkS")
		)
		(fp_rect
			(start -1.524 1.9558)
			(end 1.524 -1.9558)
			(stroke
				(width 0)
				(type default)
			)
			(fill no)
			(layer "F.CrtYd")
		)
		(fp_poly
			(pts
				(xy -1.524 -1.9558) (xy 1.524 -1.9558) (xy 1.524 1.9558) (xy -1.524 1.9558)
			)
			(stroke
				(width 0)
				(type default)
			)
			(fill no)
			(layer "F.Fab")
		)
		(pad "1" smd rect
			(at 0.65024 -0.8255)
			(size 0.4064 1.2192)
			(layers "F.Cu" "F.Mask" "F.Paste")
			(net "SAS2X28_B_HDD9_FLT")
		)
		(pad "2" smd rect
			(at 0 -0.8255)
			(size 0.4064 1.2192)
			(layers "F.Cu" "F.Mask" "F.Paste")
			(net "SAS2X28_A_HDD9_FLT")
		)
		(pad "3" smd rect
			(at -0.65024 -0.8255)
			(size 0.4064 1.2192)
			(layers "F.Cu" "F.Mask" "F.Paste")
			(net "GND")
		)
		(pad "4" smd rect
			(at -0.65024 0.8255)
			(size 0.4064 1.2192)
			(layers "F.Cu" "F.Mask" "F.Paste")
			(net "FLT_HDD9_DRIVE")
		)
		(pad "5" smd rect
			(at 0.65024 0.8255)
			(size 0.4064 1.2192)
			(layers "F.Cu" "F.Mask" "F.Paste")
			(net "P3V3")
		)
	)
	(footprint ""
		(layer "F.Cu")
		(at 58.801 -69.3674 180)
		(property "Reference" "Q65"
			(at 0 0 180)
			(layer "F.SilkS")
			(hide yes)
			(effects
				(font
					(size 1.27 1.27)
				)
			)
		)
		(property "Value" "2N7002-11-GP"
			(at 0.127 -8.9662 180)
			(unlocked yes)
			(layer "F.Fab")
			(hide yes)
			(effects
				(font
					(size 1.016 1.016)
					(thickness 0.1524)
				)
			)
		)
		(property "Device Type" "SOT23DGS2D4H44"
			(at 0.127 -10.4902 180)
			(unlocked yes)
			(layer "F.Fab")
			(hide yes)
			(effects
				(font
					(size 1.016 1.016)
					(thickness 0.1524)
				)
			)
		)
		(duplicate_pad_numbers_are_jumpers no)
		(fp_line
			(start 1.651 1.778)
			(end 1.651 -1.778)
			(stroke
				(width 0.1524)
				(type default)
			)
			(layer "F.SilkS")
		)
		(fp_line
			(start 1.651 -1.778)
			(end -1.651 -1.778)
			(stroke
				(width 0.1524)
				(type default)
			)
			(layer "F.SilkS")
		)
		(fp_line
			(start -1.651 1.778)
			(end 1.651 1.778)
			(stroke
				(width 0.1524)
				(type default)
			)
			(layer "F.SilkS")
		)
		(fp_line
			(start -1.651 -1.778)
			(end -1.651 1.778)
			(stroke
				(width 0.1524)
				(type default)
			)
			(layer "F.SilkS")
		)
		(fp_poly
			(pts
				(xy -1.778 1.8796) (xy -1.778 -1.8796) (xy 1.778 -1.8796) (xy 1.778 1.8796)
			)
			(stroke
				(width 0)
				(type default)
			)
			(fill no)
			(layer "F.CrtYd")
		)
		(fp_poly
			(pts
				(xy -1.778 1.8796) (xy -1.778 -1.8796) (xy 1.778 -1.8796) (xy 1.778 1.8796)
			)
			(stroke
				(width 0)
				(type default)
			)
			(fill no)
			(layer "F.Fab")
		)
		(pad "D" smd custom
			(at 0 -0.9525 180)
			(size 0.1905 0.1905)
			(layers "F.Cu" "F.Mask" "F.Paste")
			(net "HDD9_LED_G")
			(options
				(clearance outline)
				(anchor circle)
			)
			(primitives
				(gr_poly
					(pts
						(arc
							(start -0.1778 0.5715)
							(mid -0.321484 0.511984)
							(end -0.381 0.3683)
						)
						(arc
							(start -0.381 -0.3683)
							(mid -0.321484 -0.511984)
							(end -0.1778 -0.5715)
						)
						(arc
							(start 0.1778 -0.5715)
							(mid 0.321484 -0.511984)
							(end 0.381 -0.3683)
						)
						(arc
							(start 0.381 0.3683)
							(mid 0.321484 0.511984)
							(end 0.1778 0.5715)
						)
					)
					(width 0)
					(fill yes)
				)
			)
		)
		(pad "G" smd custom
			(at -0.98425 0.9525 180)
			(size 0.1905 0.1905)
			(layers "F.Cu" "F.Mask" "F.Paste")
			(net "HDD9_LED_B")
			(options
				(clearance outline)
				(anchor circle)
			)
			(primitives
				(gr_poly
					(pts
						(arc
							(start -0.1778 0.5715)
							(mid -0.321484 0.511984)
							(end -0.381 0.3683)
						)
						(arc
							(start -0.381 -0.3683)
							(mid -0.321484 -0.511984)
							(end -0.1778 -0.5715)
						)
						(arc
							(start 0.1778 -0.5715)
							(mid 0.321484 -0.511984)
							(end 0.381 -0.3683)
						)
						(arc
							(start 0.381 0.3683)
							(mid 0.321484 0.511984)
							(end 0.1778 0.5715)
						)
					)
					(width 0)
					(fill yes)
				)
			)
		)
		(pad "S" smd custom
			(at 0.98425 0.9525 180)
			(size 0.1905 0.1905)
			(layers "F.Cu" "F.Mask" "F.Paste")
			(net "GND")
			(options
				(clearance outline)
				(anchor circle)
			)
			(primitives
				(gr_poly
					(pts
						(arc
							(start -0.1778 0.5715)
							(mid -0.321484 0.511984)
							(end -0.381 0.3683)
						)
						(arc
							(start -0.381 -0.3683)
							(mid -0.321484 -0.511984)
							(end -0.1778 -0.5715)
						)
						(arc
							(start 0.1778 -0.5715)
							(mid 0.321484 -0.511984)
							(end 0.381 -0.3683)
						)
						(arc
							(start 0.381 0.3683)
							(mid 0.321484 0.511984)
							(end 0.1778 0.5715)
						)
					)
					(width 0)
					(fill yes)
				)
			)
		)
	)
)
